G04 ================== begin FILE IDENTIFICATION RECORD ==================*
G04 Layout Name:  15750-1.brd*
G04 Film Name:    BSMD*
G04 File Format:  Gerber RS274X*
G04 File Origin:  Cadence Allegro 16.5-S056*
G04 Origin Date:  Fri Dec 30 13:21:28 2016*
G04 *
G04 Layer:  VIA CLASS/PASTEMASK_BOTTOM*
G04 Layer:  PIN/PASTEMASK_BOTTOM*
G04 Layer:  PACKAGE GEOMETRY/PASTEMASK_BOTTOM*
G04 Layer:  DRAWING FORMAT/LAYER_PCB_STORY*
G04 Layer:  DRAWING FORMAT/LAYER_PAST_B*
G04 Layer:  BOARD GEOMETRY/PANEL_OUTLINE*
G04 *
G04 Offset:    (0.00 0.00)*
G04 Mirror:    No*
G04 Mode:      Positive*
G04 Rotation:  0*
G04 FullContactRelief:  No*
G04 UndefLineWidth:     6.00*
G04 ================== end FILE IDENTIFICATION RECORD ====================*
%FSLAX35Y35*MOIN*%
%IR0*IPPOS*OFA0.00000B0.00000*MIA0B0*SFA1.00000B1.00000*%
%AMMACRO16*
4,1,40,.011,.007,
.011,-.007,
.010939,-.007695,
.010759,-.008368,
.010464,-.009,
.010064,-.009571,
.009571,-.010064,
.009,-.010464,
.008368,-.010759,
.007695,-.010939,
.007,-.011,
-.007,-.011,
-.007695,-.010939,
-.008368,-.010759,
-.009,-.010464,
-.009571,-.010064,
-.010064,-.009571,
-.010464,-.009,
-.010759,-.008368,
-.010939,-.007695,
-.011,-.007,
-.011,.007,
-.010939,.007695,
-.010759,.008368,
-.010464,.009,
-.010064,.009571,
-.009571,.010064,
-.009,.010464,
-.008368,.010759,
-.007695,.010939,
-.007,.011,
.007,.011,
.007695,.010939,
.008368,.010759,
.009,.010464,
.009571,.010064,
.010064,.009571,
.010464,.009,
.010759,.008368,
.010939,.007695,
.011,.007,
0.0*
%
%ADD16MACRO16*%
%AMMACRO23*
4,1,40,.013,-.017,
-.013,-.017,
-.013695,-.016939,
-.014368,-.016759,
-.015,-.016464,
-.015571,-.016064,
-.016064,-.015571,
-.016464,-.015,
-.016759,-.014368,
-.016939,-.013695,
-.017,-.013,
-.017,.013,
-.016939,.013695,
-.016759,.014368,
-.016464,.015,
-.016064,.015571,
-.015571,.016064,
-.015,.016464,
-.014368,.016759,
-.013695,.016939,
-.013,.017,
.013,.017,
.013695,.016939,
.014368,.016759,
.015,.016464,
.015571,.016064,
.016064,.015571,
.016464,.015,
.016759,.014368,
.016939,.013695,
.017,.013,
.017,-.013,
.016939,-.013695,
.016759,-.014368,
.016464,-.015,
.016064,-.015571,
.015571,-.016064,
.015,-.016464,
.014368,-.016759,
.013695,-.016939,
.013,-.017,
0.0*
%
%ADD23MACRO23*%
%ADD11C,.04*%
%ADD12C,.028*%
%ADD10C,.086*%
%AMMACRO17*
4,1,40,.007,-.011,
-.007,-.011,
-.007695,-.010939,
-.008368,-.010759,
-.009,-.010464,
-.009571,-.010064,
-.010064,-.009571,
-.010464,-.009,
-.010759,-.008368,
-.010939,-.007695,
-.011,-.007,
-.011,.007,
-.010939,.007695,
-.010759,.008368,
-.010464,.009,
-.010064,.009571,
-.009571,.010064,
-.009,.010464,
-.008368,.010759,
-.007695,.010939,
-.007,.011,
.007,.011,
.007695,.010939,
.008368,.010759,
.009,.010464,
.009571,.010064,
.010064,.009571,
.010464,.009,
.010759,.008368,
.010939,.007695,
.011,.007,
.011,-.007,
.010939,-.007695,
.010759,-.008368,
.010464,-.009,
.010064,-.009571,
.009571,-.010064,
.009,-.010464,
.008368,-.010759,
.007695,-.010939,
.007,-.011,
0.0*
%
%ADD17MACRO17*%
%AMMACRO13*
4,1,40,-.011,-.007,
-.011,.007,
-.010939,.007695,
-.010759,.008368,
-.010464,.009,
-.010064,.009571,
-.009571,.010064,
-.009,.010464,
-.008368,.010759,
-.007695,.010939,
-.007,.011,
.007,.011,
.007695,.010939,
.008368,.010759,
.009,.010464,
.009571,.010064,
.010064,.009571,
.010464,.009,
.010759,.008368,
.010939,.007695,
.011,.007,
.011,-.007,
.010939,-.007695,
.010759,-.008368,
.010464,-.009,
.010064,-.009571,
.009571,-.010064,
.009,-.010464,
.008368,-.010759,
.007695,-.010939,
.007,-.011,
-.007,-.011,
-.007695,-.010939,
-.008368,-.010759,
-.009,-.010464,
-.009571,-.010064,
-.010064,-.009571,
-.010464,-.009,
-.010759,-.008368,
-.010939,-.007695,
-.011,-.007,
0.0*
%
%ADD13MACRO13*%
%AMMACRO25*
4,1,40,-.008,.012,
.008,.012,
.008695,.011939,
.009368,.011759,
.01,.011464,
.010571,.011064,
.011064,.010571,
.011464,.01,
.011759,.009368,
.011939,.008695,
.012,.008,
.012,-.008,
.011939,-.008695,
.011759,-.009368,
.011464,-.01,
.011064,-.010571,
.010571,-.011064,
.01,-.011464,
.009368,-.011759,
.008695,-.011939,
.008,-.012,
-.008,-.012,
-.008695,-.011939,
-.009368,-.011759,
-.01,-.011464,
-.010571,-.011064,
-.011064,-.010571,
-.011464,-.01,
-.011759,-.009368,
-.011939,-.008695,
-.012,-.008,
-.012,.008,
-.011939,.008695,
-.011759,.009368,
-.011464,.01,
-.011064,.010571,
-.010571,.011064,
-.01,.011464,
-.009368,.011759,
-.008695,.011939,
-.008,.012,
0.0*
%
%ADD25MACRO25*%
%AMMACRO26*
4,1,40,-.013,.017,
.013,.017,
.013695,.016939,
.014368,.016759,
.015,.016464,
.015571,.016064,
.016064,.015571,
.016464,.015,
.016759,.014368,
.016939,.013695,
.017,.013,
.017,-.013,
.016939,-.013695,
.016759,-.014368,
.016464,-.015,
.016064,-.015571,
.015571,-.016064,
.015,-.016464,
.014368,-.016759,
.013695,-.016939,
.013,-.017,
-.013,-.017,
-.013695,-.016939,
-.014368,-.016759,
-.015,-.016464,
-.015571,-.016064,
-.016064,-.015571,
-.016464,-.015,
-.016759,-.014368,
-.016939,-.013695,
-.017,-.013,
-.017,.013,
-.016939,.013695,
-.016759,.014368,
-.016464,.015,
-.016064,.015571,
-.015571,.016064,
-.015,.016464,
-.014368,.016759,
-.013695,.016939,
-.013,.017,
0.0*
%
%ADD26MACRO26*%
%AMMACRO18*
4,1,40,.007,-.011,
-.007,-.011,
-.007695,-.010939,
-.008368,-.010759,
-.009,-.010464,
-.009571,-.010064,
-.010064,-.009571,
-.010464,-.009,
-.010759,-.008368,
-.010939,-.007695,
-.011,-.007,
-.011,.007,
-.010939,.007695,
-.010759,.008368,
-.010464,.009,
-.010064,.009571,
-.009571,.010064,
-.009,.010464,
-.008368,.010759,
-.007695,.010939,
-.007,.011,
.007,.011,
.007695,.010939,
.008368,.010759,
.009,.010464,
.009571,.010064,
.010064,.009571,
.010464,.009,
.010759,.008368,
.010939,.007695,
.011,.007,
.011,-.007,
.010939,-.007695,
.010759,-.008368,
.010464,-.009,
.010064,-.009571,
.009571,-.010064,
.009,-.010464,
.008368,-.010759,
.007695,-.010939,
.007,-.011,
0.0*
%
%ADD18MACRO18*%
%AMMACRO14*
4,1,40,-.011,-.007,
-.011,.007,
-.010939,.007695,
-.010759,.008368,
-.010464,.009,
-.010064,.009571,
-.009571,.010064,
-.009,.010464,
-.008368,.010759,
-.007695,.010939,
-.007,.011,
.007,.011,
.007695,.010939,
.008368,.010759,
.009,.010464,
.009571,.010064,
.010064,.009571,
.010464,.009,
.010759,.008368,
.010939,.007695,
.011,.007,
.011,-.007,
.010939,-.007695,
.010759,-.008368,
.010464,-.009,
.010064,-.009571,
.009571,-.010064,
.009,-.010464,
.008368,-.010759,
.007695,-.010939,
.007,-.011,
-.007,-.011,
-.007695,-.010939,
-.008368,-.010759,
-.009,-.010464,
-.009571,-.010064,
-.010064,-.009571,
-.010464,-.009,
-.010759,-.008368,
-.010939,-.007695,
-.011,-.007,
0.0*
%
%ADD14MACRO14*%
%AMMACRO24*
4,1,40,-.008,.012,
.008,.012,
.008695,.011939,
.009368,.011759,
.01,.011464,
.010571,.011064,
.011064,.010571,
.011464,.01,
.011759,.009368,
.011939,.008695,
.012,.008,
.012,-.008,
.011939,-.008695,
.011759,-.009368,
.011464,-.01,
.011064,-.010571,
.010571,-.011064,
.01,-.011464,
.009368,-.011759,
.008695,-.011939,
.008,-.012,
-.008,-.012,
-.008695,-.011939,
-.009368,-.011759,
-.01,-.011464,
-.010571,-.011064,
-.011064,-.010571,
-.011464,-.01,
-.011759,-.009368,
-.011939,-.008695,
-.012,-.008,
-.012,.008,
-.011939,.008695,
-.011759,.009368,
-.011464,.01,
-.011064,.010571,
-.010571,.011064,
-.01,.011464,
-.009368,.011759,
-.008695,.011939,
-.008,.012,
0.0*
%
%ADD24MACRO24*%
%AMMACRO27*
4,1,40,-.013,.017,
.013,.017,
.013695,.016939,
.014368,.016759,
.015,.016464,
.015571,.016064,
.016064,.015571,
.016464,.015,
.016759,.014368,
.016939,.013695,
.017,.013,
.017,-.013,
.016939,-.013695,
.016759,-.014368,
.016464,-.015,
.016064,-.015571,
.015571,-.016064,
.015,-.016464,
.014368,-.016759,
.013695,-.016939,
.013,-.017,
-.013,-.017,
-.013695,-.016939,
-.014368,-.016759,
-.015,-.016464,
-.015571,-.016064,
-.016064,-.015571,
-.016464,-.015,
-.016759,-.014368,
-.016939,-.013695,
-.017,-.013,
-.017,.013,
-.016939,.013695,
-.016759,.014368,
-.016464,.015,
-.016064,.015571,
-.015571,.016064,
-.015,.016464,
-.014368,.016759,
-.013695,.016939,
-.013,.017,
0.0*
%
%ADD27MACRO27*%
%ADD34R,.157X.15*%
%ADD32R,.069X.02*%
%ADD33R,.073X.035*%
%ADD28R,.045X.055*%
%ADD30R,.016X.048*%
%ADD21R,.055X.045*%
%AMMACRO29*
4,1,40,.012,.008,
.012,-.008,
.011939,-.008695,
.011759,-.009368,
.011464,-.01,
.011064,-.010571,
.010571,-.011064,
.01,-.011464,
.009368,-.011759,
.008695,-.011939,
.008,-.012,
-.008,-.012,
-.008695,-.011939,
-.009368,-.011759,
-.01,-.011464,
-.010571,-.011064,
-.011064,-.010571,
-.011464,-.01,
-.011759,-.009368,
-.011939,-.008695,
-.012,-.008,
-.012,.008,
-.011939,.008695,
-.011759,.009368,
-.011464,.01,
-.011064,.010571,
-.010571,.011064,
-.01,.011464,
-.009368,.011759,
-.008695,.011939,
-.008,.012,
.008,.012,
.008695,.011939,
.009368,.011759,
.01,.011464,
.010571,.011064,
.011064,.010571,
.011464,.01,
.011759,.009368,
.011939,.008695,
.012,.008,
0.0*
%
%ADD29MACRO29*%
%AMMACRO19*
4,1,40,-.007,.011,
.007,.011,
.007695,.010939,
.008368,.010759,
.009,.010464,
.009571,.010064,
.010064,.009571,
.010464,.009,
.010759,.008368,
.010939,.007695,
.011,.007,
.011,-.007,
.010939,-.007695,
.010759,-.008368,
.010464,-.009,
.010064,-.009571,
.009571,-.010064,
.009,-.010464,
.008368,-.010759,
.007695,-.010939,
.007,-.011,
-.007,-.011,
-.007695,-.010939,
-.008368,-.010759,
-.009,-.010464,
-.009571,-.010064,
-.010064,-.009571,
-.010464,-.009,
-.010759,-.008368,
-.010939,-.007695,
-.011,-.007,
-.011,.007,
-.010939,.007695,
-.010759,.008368,
-.010464,.009,
-.010064,.009571,
-.009571,.010064,
-.009,.010464,
-.008368,.010759,
-.007695,.010939,
-.007,.011,
0.0*
%
%ADD19MACRO19*%
%AMMACRO15*
4,1,40,.011,.007,
.011,-.007,
.010939,-.007695,
.010759,-.008368,
.010464,-.009,
.010064,-.009571,
.009571,-.010064,
.009,-.010464,
.008368,-.010759,
.007695,-.010939,
.007,-.011,
-.007,-.011,
-.007695,-.010939,
-.008368,-.010759,
-.009,-.010464,
-.009571,-.010064,
-.010064,-.009571,
-.010464,-.009,
-.010759,-.008368,
-.010939,-.007695,
-.011,-.007,
-.011,.007,
-.010939,.007695,
-.010759,.008368,
-.010464,.009,
-.010064,.009571,
-.009571,.010064,
-.009,.010464,
-.008368,.010759,
-.007695,.010939,
-.007,.011,
.007,.011,
.007695,.010939,
.008368,.010759,
.009,.010464,
.009571,.010064,
.010064,.009571,
.010464,.009,
.010759,.008368,
.010939,.007695,
.011,.007,
0.0*
%
%ADD15MACRO15*%
%AMMACRO22*
4,1,40,.013,-.017,
-.013,-.017,
-.013695,-.016939,
-.014368,-.016759,
-.015,-.016464,
-.015571,-.016064,
-.016064,-.015571,
-.016464,-.015,
-.016759,-.014368,
-.016939,-.013695,
-.017,-.013,
-.017,.013,
-.016939,.013695,
-.016759,.014368,
-.016464,.015,
-.016064,.015571,
-.015571,.016064,
-.015,.016464,
-.014368,.016759,
-.013695,.016939,
-.013,.017,
.013,.017,
.013695,.016939,
.014368,.016759,
.015,.016464,
.015571,.016064,
.016064,.015571,
.016464,.015,
.016759,.014368,
.016939,.013695,
.017,.013,
.017,-.013,
.016939,-.013695,
.016759,-.014368,
.016464,-.015,
.016064,-.015571,
.015571,-.016064,
.015,-.016464,
.014368,-.016759,
.013695,-.016939,
.013,-.017,
0.0*
%
%ADD22MACRO22*%
%AMMACRO31*
4,1,40,.012,.008,
.012,-.008,
.011939,-.008695,
.011759,-.009368,
.011464,-.01,
.011064,-.010571,
.010571,-.011064,
.01,-.011464,
.009368,-.011759,
.008695,-.011939,
.008,-.012,
-.008,-.012,
-.008695,-.011939,
-.009368,-.011759,
-.01,-.011464,
-.010571,-.011064,
-.011064,-.010571,
-.011464,-.01,
-.011759,-.009368,
-.011939,-.008695,
-.012,-.008,
-.012,.008,
-.011939,.008695,
-.011759,.009368,
-.011464,.01,
-.011064,.010571,
-.010571,.011064,
-.01,.011464,
-.009368,.011759,
-.008695,.011939,
-.008,.012,
.008,.012,
.008695,.011939,
.009368,.011759,
.01,.011464,
.010571,.011064,
.011064,.010571,
.011464,.01,
.011759,.009368,
.011939,.008695,
.012,.008,
0.0*
%
%ADD31MACRO31*%
%AMMACRO20*
4,1,40,-.007,.011,
.007,.011,
.007695,.010939,
.008368,.010759,
.009,.010464,
.009571,.010064,
.010064,.009571,
.010464,.009,
.010759,.008368,
.010939,.007695,
.011,.007,
.011,-.007,
.010939,-.007695,
.010759,-.008368,
.010464,-.009,
.010064,-.009571,
.009571,-.010064,
.009,-.010464,
.008368,-.010759,
.007695,-.010939,
.007,-.011,
-.007,-.011,
-.007695,-.010939,
-.008368,-.010759,
-.009,-.010464,
-.009571,-.010064,
-.010064,-.009571,
-.010464,-.009,
-.010759,-.008368,
-.010939,-.007695,
-.011,-.007,
-.011,.007,
-.010939,.007695,
-.010759,.008368,
-.010464,.009,
-.010064,.009571,
-.009571,.010064,
-.009,.010464,
-.008368,.010759,
-.007695,.010939,
-.007,.011,
0.0*
%
%ADD20MACRO20*%
%ADD35C,.02*%
%ADD36C,.006*%
G75*
%LPD*%
G75*
G54D10*
X26087Y-114844D03*
X26435Y373984D03*
X175335Y62719D03*
Y189062D03*
X547104Y69007D03*
Y195351D03*
X696192Y373984D03*
G54D20*
X119800Y293000D03*
X205800Y309500D03*
X254800Y88500D03*
X245300Y156500D03*
Y152500D03*
X254800Y197000D03*
G54D11*
X22401Y341025D03*
X291000Y22500D03*
X316610Y341025D03*
G54D21*
X155811Y305700D03*
Y313300D03*
G54D30*
X270940Y162250D03*
Y155750D03*
X273500Y162250D03*
X276060D03*
Y155750D03*
G54D12*
X62500Y279500D03*
X67050Y338239D03*
X96400Y292250D03*
X100250Y324750D03*
X122500Y296600D03*
X112500Y302000D03*
X120750Y324544D03*
X107300Y317000D03*
X118500Y318500D03*
X111400Y311750D03*
X109500Y330500D03*
X119500Y330000D03*
X135000Y293000D03*
X136500Y311500D03*
X139500Y321000D03*
X125100Y340250D03*
X161311Y302000D03*
X165811Y308000D03*
X163500Y313300D03*
X181061Y302000D03*
X177811Y309500D03*
X173811Y324500D03*
Y315000D03*
X195561Y304250D03*
X202911Y296500D03*
X237500Y92000D03*
X239500Y43500D03*
X249000Y65000D03*
X252000Y82338D03*
X252500Y103000D03*
X249000Y132500D03*
X254500Y148500D03*
X255500Y153500D03*
X240500Y150000D03*
X240437Y161999D03*
X240300Y168500D03*
X252000Y191000D03*
X249000Y185000D03*
X252500Y211500D03*
X249000Y241000D03*
X244000Y277500D03*
X259500Y82338D03*
X257000Y92500D03*
X256500Y100000D03*
Y106000D03*
X267000Y131693D03*
X259500Y191000D03*
X256500Y208500D03*
Y201000D03*
Y214500D03*
X266500Y244000D03*
X263000Y318500D03*
X284000Y107392D03*
X274750Y140500D03*
X283000Y143000D03*
X284662Y170000D03*
X287500Y186500D03*
X276500Y197000D03*
X295311Y123500D03*
X290500Y139875D03*
X294000Y166500D03*
X316500Y249500D03*
Y320500D03*
G54D31*
X258800Y164500D03*
G54D22*
X143511Y313500D03*
X205011Y314000D03*
G54D13*
X99000Y284200D03*
X95000D03*
X110000D03*
X114000D03*
X117500Y341200D03*
X121500D03*
X168311Y301700D03*
X172311D03*
X176311D03*
X199811Y304200D03*
X233311Y152700D03*
X229311Y160200D03*
X233311Y167700D03*
X264500Y164700D03*
X266500Y240200D03*
X270500D03*
G54D32*
X320394Y46752D03*
Y49902D03*
Y53051D03*
Y56201D03*
Y59351D03*
Y62500D03*
Y65650D03*
Y68799D03*
Y71949D03*
Y75099D03*
Y78248D03*
Y81398D03*
Y84548D03*
Y87697D03*
Y90847D03*
Y93996D03*
Y97146D03*
Y100296D03*
Y103445D03*
Y106595D03*
Y109744D03*
Y112894D03*
Y116044D03*
Y119193D03*
Y122343D03*
Y125492D03*
Y128642D03*
X310118Y120670D03*
Y123820D03*
Y126969D03*
X320394Y131792D03*
Y134941D03*
Y138091D03*
Y141240D03*
Y144390D03*
X310118Y130119D03*
Y133268D03*
Y136418D03*
X320394Y147540D03*
Y150689D03*
Y153839D03*
Y156988D03*
Y160138D03*
Y163288D03*
Y166437D03*
Y169587D03*
G54D14*
X99000Y280800D03*
X95000D03*
X110000D03*
X114000D03*
X117500Y337800D03*
X121500D03*
X168311Y298300D03*
X172311D03*
X176311D03*
X199811Y300800D03*
X233311Y149300D03*
X229311Y156800D03*
X233311Y164300D03*
X264500Y161300D03*
X266500Y236800D03*
X270500D03*
G54D23*
X149111Y313500D03*
X210611Y314000D03*
G54D15*
X100000Y292300D03*
X100500Y302300D03*
X96500D03*
X104500D03*
X92500D03*
X119000Y308300D03*
X115000D03*
X109000Y337800D03*
X113500D03*
X218311Y304300D03*
X233311Y156800D03*
X229311Y149300D03*
Y164300D03*
X282500Y161300D03*
G54D33*
X310315Y46142D03*
Y51142D03*
Y56142D03*
Y61142D03*
Y66142D03*
Y71142D03*
Y76142D03*
Y81142D03*
Y86142D03*
Y91142D03*
Y96142D03*
Y101142D03*
Y106142D03*
Y111142D03*
Y116142D03*
Y141142D03*
Y146142D03*
Y151142D03*
Y156142D03*
Y161142D03*
Y166142D03*
Y171142D03*
G54D24*
X222311Y307800D03*
X264500Y156800D03*
G54D34*
X334252Y13307D03*
Y203977D03*
G54D25*
X222311Y304200D03*
X264500Y153200D03*
G54D16*
X100000Y295700D03*
X100500Y305700D03*
X96500D03*
X104500D03*
X92500D03*
X119000Y311700D03*
X115000D03*
X109000Y341200D03*
X113500D03*
X218311Y307700D03*
X233311Y160200D03*
X229311Y152700D03*
Y167700D03*
X282500Y164700D03*
G54D35*
G01X-176139Y-183003D02*
G02I-12000J0D01*
G01X-181289D02*
G02I-6850J0D01*
G01X-172139D02*
X-204139D01*
G01X-188139Y-199003D02*
Y-167003D01*
G01X-172139Y-199003D02*
Y-279003D01*
G01D02*
X1178561D01*
G01X-172139Y-234503D02*
X1178561D01*
G01X-172139Y-199003D02*
X1178561D01*
G01X391061D02*
Y-279003D01*
G01X528561Y-199003D02*
Y-279003D01*
G01X643561Y-199003D02*
Y-279003D01*
G01X811061Y-199003D02*
Y-279003D01*
G01X981061Y-199003D02*
Y-279003D01*
G01X1178561Y-199003D02*
Y-279003D01*
G01X1210561Y-183003D02*
X1178561D01*
G01X1206561D02*
G02I-12000J0D01*
G01X1201411D02*
G02I-6850J0D01*
G01X1194561Y-199003D02*
Y-167003D01*
G54D26*
X213800Y320000D03*
G54D17*
X96800Y317000D03*
Y321000D03*
X193611Y317000D03*
X254800Y96500D03*
Y205000D03*
X271300Y131500D03*
Y135500D03*
X255300Y160500D03*
G54D36*
G01X-148956Y-251503D02*
Y-269003D01*
X-140222D01*
G01X-127089Y-257337D02*
Y-269003D01*
G01Y-252670D02*
X-127526Y-252378D01*
Y-251795D01*
X-127089Y-251503D01*
X-126652Y-251795D01*
Y-252378D01*
X-127089Y-252670D01*
G01X-112646Y-273378D02*
X-111117Y-274545D01*
X-109371Y-274836D01*
X-107843Y-274545D01*
X-106532Y-273087D01*
X-105659Y-271045D01*
Y-257337D01*
G01Y-259670D02*
X-106532Y-258503D01*
X-107843Y-257628D01*
X-109371Y-257337D01*
X-111117Y-257920D01*
X-112209Y-259086D01*
X-113083Y-261128D01*
X-113519Y-263170D01*
X-113301Y-264920D01*
X-112427Y-266962D01*
X-111117Y-268420D01*
X-109371Y-269003D01*
X-108061Y-268711D01*
X-106532Y-267545D01*
X-105659Y-266379D01*
G01X-95801Y-269003D02*
Y-251503D01*
G01Y-259961D02*
X-94709Y-258503D01*
X-93617Y-257628D01*
X-91871Y-257337D01*
X-90561Y-257628D01*
X-89032Y-258795D01*
X-88377Y-260545D01*
Y-269003D01*
G01X-74589Y-251503D02*
Y-269003D01*
G01X-77646Y-257337D02*
X-71532D01*
G01X-60801Y-269003D02*
Y-257337D01*
G01Y-260253D02*
X-59927Y-258795D01*
X-58617Y-257628D01*
X-56871Y-257337D01*
X-55343Y-257628D01*
X-54032Y-258795D01*
X-53377Y-260836D01*
Y-269003D01*
G01X-39589Y-257337D02*
Y-269003D01*
G01Y-252670D02*
X-40026Y-252378D01*
Y-251795D01*
X-39589Y-251503D01*
X-39152Y-251795D01*
Y-252378D01*
X-39589Y-252670D01*
G01X-25801Y-269003D02*
Y-257337D01*
G01Y-260253D02*
X-24927Y-258795D01*
X-23617Y-257628D01*
X-21871Y-257337D01*
X-20343Y-257628D01*
X-19032Y-258795D01*
X-18377Y-260836D01*
Y-269003D01*
G01X-7646Y-273378D02*
X-6117Y-274545D01*
X-4371Y-274836D01*
X-2843Y-274545D01*
X-1532Y-273087D01*
X-659Y-271045D01*
Y-257337D01*
G01Y-259670D02*
X-1532Y-258503D01*
X-2843Y-257628D01*
X-4371Y-257337D01*
X-6117Y-257920D01*
X-7209Y-259086D01*
X-8083Y-261128D01*
X-8519Y-263170D01*
X-8301Y-264920D01*
X-7427Y-266962D01*
X-6117Y-268420D01*
X-4371Y-269003D01*
X-3061Y-268711D01*
X-1532Y-267545D01*
X-659Y-266379D01*
G01X26044Y-269003D02*
Y-251503D01*
X31284D01*
X33031Y-252378D01*
X34341Y-254420D01*
X34778Y-256753D01*
X34341Y-259086D01*
X33249Y-260836D01*
X31284Y-261712D01*
X26044D01*
G01X42452Y-251503D02*
X47911Y-269003D01*
X53370Y-251503D01*
G01X65411D02*
Y-269003D01*
G01X60389Y-251503D02*
X70433D01*
G01X94734Y-269003D02*
Y-251503D01*
X100411Y-266086D01*
X106088Y-251503D01*
Y-269003D01*
G01X117911Y-269586D02*
X117474Y-269295D01*
Y-268711D01*
X117911Y-268420D01*
X118348Y-268711D01*
Y-269295D01*
X117911Y-269586D01*
G01X131263Y-254420D02*
X132573Y-252670D01*
X134101Y-251795D01*
X135848Y-251503D01*
X138031Y-252086D01*
X139559Y-253545D01*
X139996Y-255294D01*
X139778Y-257045D01*
X138904Y-258503D01*
X134538Y-261420D01*
X132573Y-263461D01*
X131263Y-266379D01*
X130826Y-269003D01*
X139996D01*
G01X164952D02*
X170411Y-251503D01*
X175870Y-269003D01*
G01X173904Y-262878D02*
X166917D01*
G01X191841Y-251503D02*
Y-269003D01*
G01Y-266379D02*
X190968Y-267837D01*
X189657Y-268711D01*
X188129Y-269003D01*
X186383Y-268420D01*
X185073Y-266962D01*
X184199Y-265212D01*
X183981Y-263170D01*
X184199Y-261128D01*
X185073Y-259378D01*
X186383Y-257920D01*
X188129Y-257337D01*
X189657Y-257628D01*
X190749Y-258212D01*
X191841Y-259378D01*
G01X209341Y-269003D02*
Y-257337D01*
G01Y-259378D02*
X208468Y-258212D01*
X207157Y-257628D01*
X205629Y-257337D01*
X204101Y-257920D01*
X202791Y-259086D01*
X201917Y-260836D01*
X201481Y-263170D01*
X201917Y-265503D01*
X202791Y-267253D01*
X204101Y-268420D01*
X205629Y-269003D01*
X207157Y-268711D01*
X208468Y-267837D01*
X209341Y-266670D01*
G01X218981Y-274836D02*
Y-257337D01*
G01Y-259961D02*
X220073Y-258503D01*
X221164Y-257628D01*
X222911Y-257337D01*
X224439Y-257628D01*
X225968Y-259086D01*
X226623Y-261128D01*
X226841Y-263170D01*
X226623Y-265212D01*
X225968Y-267253D01*
X224657Y-268420D01*
X222911Y-269003D01*
X221383Y-268711D01*
X219854Y-267837D01*
X218981Y-266670D01*
G01X240411Y-251503D02*
Y-269003D01*
G01X237354Y-257337D02*
X243468D01*
G01X257911Y-269003D02*
X256601Y-268711D01*
X255291Y-267545D01*
X254417Y-265503D01*
X253981Y-263170D01*
X254417Y-260836D01*
X255291Y-258795D01*
X256601Y-257628D01*
X257911Y-257337D01*
X259221Y-257628D01*
X260531Y-258795D01*
X261404Y-260836D01*
X261623Y-263170D01*
X261404Y-265503D01*
X260531Y-267545D01*
X259221Y-268711D01*
X257911Y-269003D01*
G01X272354D02*
Y-257337D01*
G01Y-259670D02*
X273446Y-258503D01*
X274538Y-257628D01*
X276066Y-257337D01*
X277157Y-257628D01*
X278468Y-258503D01*
G01X315214Y-252962D02*
X313904Y-252086D01*
X312376Y-251503D01*
X310629D01*
X308664Y-252378D01*
X307136Y-253836D01*
X306044Y-255587D01*
X305171Y-258503D01*
X304952Y-261128D01*
X305389Y-263753D01*
X306044Y-265503D01*
X307354Y-267253D01*
X308883Y-268420D01*
X310411Y-269003D01*
X311939D01*
X313468Y-268420D01*
X314778Y-267545D01*
X315870Y-266379D01*
G01X331841Y-269003D02*
Y-257337D01*
G01Y-259378D02*
X330968Y-258212D01*
X329657Y-257628D01*
X328129Y-257337D01*
X326601Y-257920D01*
X325291Y-259086D01*
X324417Y-260836D01*
X323981Y-263170D01*
X324417Y-265503D01*
X325291Y-267253D01*
X326601Y-268420D01*
X328129Y-269003D01*
X329657Y-268711D01*
X330968Y-267837D01*
X331841Y-266670D01*
G01X342354Y-269003D02*
Y-257337D01*
G01Y-259670D02*
X343446Y-258503D01*
X344538Y-257628D01*
X346066Y-257337D01*
X347157Y-257628D01*
X348468Y-258503D01*
G01X366841Y-251503D02*
Y-269003D01*
G01Y-266379D02*
X365968Y-267837D01*
X364657Y-268711D01*
X363129Y-269003D01*
X361383Y-268420D01*
X360073Y-266962D01*
X359199Y-265212D01*
X358981Y-263170D01*
X359199Y-261128D01*
X360073Y-259378D01*
X361383Y-257920D01*
X363129Y-257337D01*
X364657Y-257628D01*
X365749Y-258212D01*
X366841Y-259378D01*
G01X-1Y-113228D02*
Y-117165D01*
G03X7873Y-125039I7874J0D01*
G01X714566D01*
G03X722440Y-117165I0J7874D01*
G01Y-113228D01*
G01X1968Y40473D02*
X9842D01*
G02X11811Y38504I0J-1969D01*
G01Y-16772D01*
G02X9842Y-18740I-1969J1D01*
G01X1968D01*
G03X0Y-20709I0J-1968D01*
G01Y-97480D01*
G03X7874Y-105354I7874J0D01*
G01X341535D01*
G03X349409Y-97480I0J7874D01*
G01Y-15748D01*
G03X341535Y-7874I-7874J0D01*
G01X141338D01*
G02X133464Y0I0J7874D01*
G01Y250197D01*
G03X125590Y258071I-7874J0D01*
G01X1968D01*
G03X0Y256102I0J-1968D01*
G01Y236673D01*
G03X1968Y234705I1968J0D01*
G01X28346D01*
G02X30315Y232736I0J-1969D01*
G01Y216004D01*
G02X28346Y214036I-1968J0D01*
G01X23228D01*
G03X21259Y212067I0J-1969D01*
G01Y86752D01*
G03X23228Y84784I1969J1D01*
G01X28346D01*
G02X30315Y82815I0J-1969D01*
G01Y66083D01*
G02X28346Y64114I-1969J0D01*
G01X1968D01*
G03X0Y62146I0J-1968D01*
G01Y42441D01*
G03X1968Y40473I1968J0D01*
G01X-1Y-113228D02*
X13591D01*
G01X347441Y217598D02*
X339567D01*
G02X337598Y219567I0J1969D01*
G01Y274843D01*
G02X339567Y276811I1969J-1D01*
G01X347441D01*
G03X349409Y278780I0J1968D01*
G01Y355551D01*
G03X341535Y363425I-7874J0D01*
G01X7874D01*
G03X0Y355551I0J-7874D01*
G01Y273819D01*
G03X7874Y265945I7874J0D01*
G01X208071D01*
G02X215945Y258071I0J-7874D01*
G01Y7874D01*
G03X223819Y0I7874J0D01*
G01X347441D01*
G03X349409Y1969I0J1968D01*
G01Y21398D01*
G03X347441Y23366I-1968J0D01*
G01X321063D01*
G02X319094Y25335I0J1969D01*
G01Y42067D01*
G02X321063Y44035I1969J-1D01*
G01X326181D01*
G03X328150Y46004I0J1969D01*
G01Y171319D01*
G03X326181Y173287I-1968J0D01*
G01X321063D01*
G02X319094Y175256I0J1969D01*
G01Y191988D01*
G02X321063Y193957I1969J0D01*
G01X347441D01*
G03X349409Y195925I0J1968D01*
G01Y215630D01*
G03X347441Y217598I-1968J0D01*
G01X245745Y383110D02*
X7874D01*
G03X0Y375236I0J-7874D01*
G01Y371299D01*
G01D02*
X13591D01*
G01Y-113228D02*
G03Y-105354I0J3937D01*
G01Y258071D02*
G03Y265945I0J3937D01*
G01Y363425D02*
G03Y371299I0J3937D01*
G01X38787Y-113228D02*
X237000D01*
G01X38787Y-105354D02*
G03Y-113228I1J-3937D01*
G01Y265945D02*
G03Y258071I1J-3937D01*
G01X237000Y371299D02*
X38787D01*
G01D02*
G03Y363425I1J-3937D01*
G01X68484Y-224003D02*
Y-206503D01*
X74161Y-221086D01*
X79838Y-206503D01*
Y-224003D01*
G01X91661D02*
X90351Y-223711D01*
X89041Y-222545D01*
X88167Y-220503D01*
X87731Y-218170D01*
X88167Y-215836D01*
X89041Y-213795D01*
X90351Y-212628D01*
X91661Y-212337D01*
X92971Y-212628D01*
X94281Y-213795D01*
X95154Y-215836D01*
X95373Y-218170D01*
X95154Y-220503D01*
X94281Y-222545D01*
X92971Y-223711D01*
X91661Y-224003D01*
G01X113091Y-206503D02*
Y-224003D01*
G01Y-221379D02*
X112218Y-222837D01*
X110907Y-223711D01*
X109379Y-224003D01*
X107633Y-223420D01*
X106323Y-221962D01*
X105449Y-220212D01*
X105231Y-218170D01*
X105449Y-216128D01*
X106323Y-214378D01*
X107633Y-212920D01*
X109379Y-212337D01*
X110907Y-212628D01*
X111999Y-213212D01*
X113091Y-214378D01*
G01X123386Y-216128D02*
X130373D01*
X129718Y-214086D01*
X128626Y-212920D01*
X127098Y-212337D01*
X125569Y-212628D01*
X124259Y-213503D01*
X123386Y-215545D01*
X122949Y-217295D01*
Y-219045D01*
X123386Y-220795D01*
X124478Y-222545D01*
X125788Y-223711D01*
X127316Y-224003D01*
X128844Y-223420D01*
X130373Y-221670D01*
G01X144161Y-224003D02*
Y-206503D01*
G01X141338Y116437D02*
G03X133464I-3937J0D01*
G01Y141634D02*
G03X141338I3937J0D01*
G01Y0D02*
Y116437D01*
G01X162106Y0D02*
X141337D01*
G01X141338Y141634D02*
Y258071D01*
G01D02*
X162106D01*
G01Y-7874D02*
G03Y0I0J3937D01*
G01X179626Y62719D02*
G03X171044I-4291J0D01*
G03X179626I4291J0D01*
G01Y189063D02*
G03X171044Y189062I-4291J0D01*
G03X179626Y189063I4291J1D01*
G01X162106Y258071D02*
G03Y265945I0J3937D01*
G01X187302Y0D02*
G03Y-7874I1J-3937D01*
G01X208071Y0D02*
X187302D01*
G01Y265945D02*
G03Y258071I1J-3937D01*
G01D02*
X208071D01*
G01X207913Y0D02*
X208071D01*
G01Y116437D02*
Y0D01*
G01X215945Y116437D02*
G03X208071I-3937J0D01*
G01Y141634D02*
G03X215945I3937J0D01*
G01X208071Y258071D02*
Y141634D01*
G01X237000Y-113228D02*
G03Y-105354I0J3937D01*
G01Y363425D02*
G03Y371299I0J3937D01*
G01X245745Y383110D02*
G03X253619I3937J0D01*
G01X722440Y371299D02*
Y375236D01*
G03X714566Y383110I-7874J0D01*
G01X253619D01*
G01X262196Y-113228D02*
X460244D01*
G01X262196Y-105354D02*
G03Y-113228I0J-3937D01*
G01Y371299D02*
X460244D01*
G01X262196D02*
G03Y363425I0J-3937D01*
G01X310621Y-7874D02*
G03Y0I0J3937D01*
G01X335817D02*
G03Y-7874I1J-3937D01*
G01X353346Y-47481D02*
G03X349409Y-51418I0J-3937D01*
G01Y-20709D02*
G03X353346Y-24646I3937J0D01*
G01Y282717D02*
G03X349409Y278780I0J-3937D01*
G01Y309489D02*
G03X353346Y305552I3937J0D01*
G01Y-47481D02*
X369094D01*
G01X373031Y-51418D02*
G03X369094Y-47481I-3937J0D01*
G01X353346Y-24646D02*
X369094D01*
G01D02*
G03X373031Y-20709I0J3937D01*
G01X353346Y282717D02*
X369094D01*
G01X373031Y278780D02*
G03X369094Y282717I-3937J0D01*
G01X353346Y305552D02*
X369094D01*
G01D02*
G03X373031Y309489I0J3937D01*
G01X374999Y40473D02*
X382873D01*
G02X384842Y38504I0J-1969D01*
G01Y-16772D01*
G02X382873Y-18740I-1969J1D01*
G01X374999D01*
G03X373031Y-20709I0J-1968D01*
G01Y-97480D01*
G03X380905Y-105354I7874J0D01*
G01X714566D01*
G03X722440Y-97480I0J7874D01*
G01Y-15748D01*
G03X714566Y-7874I-7874J0D01*
G01X514369D01*
G02X506495Y0I0J7874D01*
G01Y250197D01*
G03X498621Y258071I-7874J0D01*
G01X374999D01*
G03X373031Y256102I0J-1968D01*
G01Y236673D01*
G03X374999Y234705I1968J0D01*
G01X401377D01*
G02X403346Y232736I0J-1969D01*
G01Y216004D01*
G02X401377Y214036I-1968J0D01*
G01X396259D01*
G03X394290Y212067I0J-1969D01*
G01Y86752D01*
G03X396259Y84784I1969J1D01*
G01X401377D01*
G02X403346Y82815I0J-1969D01*
G01Y66083D01*
G02X401377Y64114I-1969J0D01*
G01X374999D01*
G03X373031Y62146I0J-1968D01*
G01Y42441D01*
G03X374999Y40473I1968J0D01*
G01X720472Y217598D02*
X712598D01*
G02X710629Y219567I0J1969D01*
G01Y274843D01*
G02X712598Y276811I1969J-1D01*
G01X720472D01*
G03X722440Y278780I0J1968D01*
G01Y355551D01*
G03X714566Y363425I-7874J0D01*
G01X380905D01*
G03X373031Y355551I0J-7874D01*
G01Y273819D01*
G03X380905Y265945I7874J0D01*
G01X581102D01*
G02X588976Y258071I0J-7874D01*
G01Y7874D01*
G03X596850Y0I7874J0D01*
G01X720472D01*
G03X722440Y1969I0J1968D01*
G01Y21398D01*
G03X720472Y23366I-1968J0D01*
G01X694094D01*
G02X692125Y25335I0J1969D01*
G01Y42067D01*
G02X694094Y44035I1969J-1D01*
G01X699212D01*
G03X701181Y46004I0J1969D01*
G01Y171319D01*
G03X699212Y173287I-1969J-1D01*
G01X694094D01*
G02X692125Y175256I0J1969D01*
G01Y191988D01*
G02X694094Y193957I1969J0D01*
G01X720472D01*
G03X722440Y195925I0J1968D01*
G01Y215630D01*
G03X720472Y217598I-1968J0D01*
G01X386622Y258071D02*
G03Y265945I0J3937D01*
G01X424761Y-269003D02*
Y-251503D01*
X422141Y-255003D01*
G01Y-269003D02*
X427381D01*
G01X437458Y-266379D02*
X438767Y-267837D01*
X440296Y-268711D01*
X442261Y-269003D01*
X444226Y-268420D01*
X445754Y-267253D01*
X446846Y-265212D01*
X447064Y-262878D01*
X446628Y-260545D01*
X445536Y-259086D01*
X444007Y-257920D01*
X442479Y-257628D01*
X440951Y-257920D01*
X438986Y-259086D01*
X439641Y-251503D01*
X445536D01*
G01X459324Y-269003D02*
X459761Y-265212D01*
X460416Y-262003D01*
X461289Y-259086D01*
X462381Y-255878D01*
X464128Y-251503D01*
X455394D01*
G01X472458Y-266379D02*
X473767Y-267837D01*
X475296Y-268711D01*
X477261Y-269003D01*
X479226Y-268420D01*
X480754Y-267253D01*
X481846Y-265212D01*
X482064Y-262878D01*
X481628Y-260545D01*
X480536Y-259086D01*
X479007Y-257920D01*
X477479Y-257628D01*
X475951Y-257920D01*
X473986Y-259086D01*
X474641Y-251503D01*
X480536D01*
G01X494761D02*
X493014Y-252086D01*
X491704Y-253545D01*
X490831Y-255294D01*
X490176Y-257628D01*
X489958Y-260253D01*
X490176Y-262878D01*
X490831Y-265212D01*
X491704Y-266962D01*
X493014Y-268420D01*
X494761Y-269003D01*
X496507Y-268420D01*
X497818Y-266962D01*
X498691Y-265212D01*
X499346Y-262878D01*
X499564Y-260253D01*
X499346Y-257628D01*
X498691Y-255294D01*
X497818Y-253545D01*
X496507Y-252086D01*
X494761Y-251503D01*
G01X411644Y-224003D02*
Y-206503D01*
X416884D01*
X418631Y-207378D01*
X419941Y-209420D01*
X420378Y-211753D01*
X419941Y-214086D01*
X418849Y-215836D01*
X416884Y-216712D01*
X411644D01*
G01X438314Y-207962D02*
X437004Y-207086D01*
X435476Y-206503D01*
X433729D01*
X431764Y-207378D01*
X430236Y-208836D01*
X429144Y-210587D01*
X428271Y-213503D01*
X428052Y-216128D01*
X428489Y-218753D01*
X429144Y-220503D01*
X430454Y-222253D01*
X431983Y-223420D01*
X433511Y-224003D01*
X435039D01*
X436568Y-223420D01*
X437878Y-222545D01*
X438970Y-221379D01*
G01X452757Y-214670D02*
X453631Y-213795D01*
X454286Y-212337D01*
X454723Y-210294D01*
X454286Y-208545D01*
X453413Y-207378D01*
X451884Y-206503D01*
X445989D01*
Y-224003D01*
X453194D01*
X454723Y-222837D01*
X455596Y-221086D01*
X456033Y-219045D01*
X455596Y-217003D01*
X454286Y-215253D01*
X452757Y-214670D01*
X445989D01*
G01X461961Y-229836D02*
X475061D01*
G01X480989Y-224003D02*
Y-206503D01*
X491033Y-224003D01*
Y-206503D01*
G01X503511Y-224003D02*
X501764Y-223711D01*
X500236Y-222545D01*
X498926Y-220795D01*
X498052Y-218753D01*
X497616Y-216420D01*
Y-214086D01*
X498052Y-211753D01*
X498926Y-209711D01*
X500236Y-207962D01*
X501764Y-206795D01*
X503511Y-206503D01*
X505257Y-206795D01*
X506786Y-207962D01*
X508096Y-209711D01*
X508970Y-211753D01*
X509406Y-214086D01*
Y-216420D01*
X508970Y-218753D01*
X508096Y-220795D01*
X506786Y-222545D01*
X505257Y-223711D01*
X503511Y-224003D01*
G01X411819Y265945D02*
G03Y258071I0J-3937D01*
G01X460244Y-113228D02*
G03Y-105354I0J3937D01*
G01Y363425D02*
G03Y371299I0J3937D01*
G01X485441Y-105354D02*
G03Y-113228I0J-3937D01*
G01Y371299D02*
G03Y363425I0J-3937D01*
G01Y-113228D02*
X683652D01*
G01X485441Y371299D02*
X683652D01*
G01X514369Y0D02*
Y116437D01*
G01X535137Y0D02*
X514369D01*
G01Y116437D02*
G03X506494I-3937J0D01*
G01Y141634D02*
G03X514369I3937J0D01*
G01D02*
Y258071D01*
G01D02*
X535137D01*
G01Y-7874D02*
G03Y0I0J3937D01*
G01X551396Y69008D02*
G03X542813I-4291J0D01*
G03X551396I4291J0D01*
G01Y195351D02*
G03X542813Y195352I-4292J0D01*
G03X551396Y195351I4291J-1D01*
G01X535137Y258071D02*
G03Y265945I0J3937D01*
G01X554352Y-206503D02*
X559811Y-224003D01*
X565270Y-206503D01*
G01X581678Y-224003D02*
X572944D01*
Y-206503D01*
X581678D01*
G01X578184Y-214961D02*
X572944D01*
G01X590444Y-224003D02*
Y-206503D01*
X595903D01*
X597649Y-207378D01*
X598741Y-208545D01*
X599178Y-210878D01*
X598741Y-213212D01*
X597431Y-214670D01*
X595903Y-215545D01*
X590444D01*
G01X595903D02*
X599178Y-224003D01*
G01X612311Y-224586D02*
X611874Y-224295D01*
Y-223711D01*
X612311Y-223420D01*
X612748Y-223711D01*
Y-224295D01*
X612311Y-224586D01*
G01X560333Y0D02*
G03Y-7874I1J-3937D01*
G01X581102Y0D02*
X560333D01*
G01Y265945D02*
G03Y258071I1J-3937D01*
G01D02*
X581102D01*
G01X586061Y-269003D02*
Y-251503D01*
X583441Y-255003D01*
G01Y-269003D02*
X588681D01*
G01X581102Y116437D02*
Y0D01*
G01X588976Y116437D02*
G03X581102I-3937J0D01*
G01Y141634D02*
G03X588976I3937J0D01*
G01X581102Y258071D02*
Y141634D01*
G01X751765Y-259670D02*
X750891Y-258795D01*
X750236Y-257337D01*
X749799Y-255294D01*
X750236Y-253545D01*
X751109Y-252378D01*
X752638Y-251503D01*
X758533D01*
Y-269003D01*
X751328D01*
X749799Y-267837D01*
X748926Y-266086D01*
X748489Y-264045D01*
X748926Y-262003D01*
X750236Y-260253D01*
X751765Y-259670D01*
X758533D01*
G01X740596Y-266670D02*
X738849Y-268128D01*
X736884Y-269003D01*
X735138D01*
X733391Y-268128D01*
X732081Y-266670D01*
X731426Y-264628D01*
X731863Y-262587D01*
X732954Y-260836D01*
X734919Y-259670D01*
X737539Y-259086D01*
X739068Y-257920D01*
X739723Y-255878D01*
X739286Y-253836D01*
X738194Y-252378D01*
X736666Y-251503D01*
X735138D01*
X733609Y-252086D01*
X732299Y-253545D01*
G01X724188Y-269003D02*
Y-251503D01*
X718511Y-266086D01*
X712834Y-251503D01*
Y-269003D01*
G01X705814D02*
Y-251503D01*
X701448D01*
X699701Y-252378D01*
X698391Y-253545D01*
X697299Y-255294D01*
X696426Y-257337D01*
X696208Y-260253D01*
X696426Y-263170D01*
X697299Y-265212D01*
X698391Y-266962D01*
X699701Y-268128D01*
X701448Y-269003D01*
X705814D01*
G01X687894Y-206503D02*
Y-224003D01*
X696628D01*
G01X713691D02*
Y-212337D01*
G01Y-214378D02*
X712818Y-213212D01*
X711507Y-212628D01*
X709979Y-212337D01*
X708451Y-212920D01*
X707141Y-214086D01*
X706267Y-215836D01*
X705831Y-218170D01*
X706267Y-220503D01*
X707141Y-222253D01*
X708451Y-223420D01*
X709979Y-224003D01*
X711507Y-223711D01*
X712818Y-222837D01*
X713691Y-221670D01*
G01X722676Y-229253D02*
X723986Y-229836D01*
X725733Y-229253D01*
X726824Y-228087D01*
X727698Y-226628D01*
X729007Y-221962D01*
X731846Y-212337D01*
G01X724859D02*
X729007Y-221962D01*
G01X741486Y-216128D02*
X748473D01*
X747818Y-214086D01*
X746726Y-212920D01*
X745198Y-212337D01*
X743669Y-212628D01*
X742359Y-213503D01*
X741486Y-215545D01*
X741049Y-217295D01*
Y-219045D01*
X741486Y-220795D01*
X742578Y-222545D01*
X743888Y-223711D01*
X745416Y-224003D01*
X746944Y-223420D01*
X748473Y-221670D01*
G01X759204Y-224003D02*
Y-212337D01*
G01Y-214670D02*
X760296Y-213503D01*
X761388Y-212628D01*
X762916Y-212337D01*
X764007Y-212628D01*
X765318Y-213503D01*
G01X683652Y-113228D02*
G03Y-105354I0J3937D01*
G01Y-7874D02*
G03Y0I0J3937D01*
G01Y363425D02*
G03Y371299I0J3937D01*
G01X708848Y-113228D02*
X722440D01*
G01X708848Y-105354D02*
G03Y-113228I1J-3937D01*
G01Y0D02*
G03Y-7874I1J-3937D01*
G01Y371299D02*
X722440D01*
G01X708848D02*
G03Y363425I1J-3937D01*
G01X830008Y-224003D02*
Y-206503D01*
X834374D01*
X836121Y-207378D01*
X837431Y-208545D01*
X838523Y-210294D01*
X839396Y-212337D01*
X839614Y-215253D01*
X839396Y-218170D01*
X838523Y-220212D01*
X837431Y-221962D01*
X836121Y-223128D01*
X834374Y-224003D01*
X830008D01*
G01X849036Y-216128D02*
X856023D01*
X855368Y-214086D01*
X854276Y-212920D01*
X852748Y-212337D01*
X851219Y-212628D01*
X849909Y-213503D01*
X849036Y-215545D01*
X848599Y-217295D01*
Y-219045D01*
X849036Y-220795D01*
X850128Y-222545D01*
X851438Y-223711D01*
X852966Y-224003D01*
X854494Y-223420D01*
X856023Y-221670D01*
G01X866536Y-221962D02*
X867628Y-223128D01*
X869156Y-224003D01*
X870466D01*
X871776Y-223420D01*
X872649Y-222545D01*
X873086Y-221379D01*
X872868Y-219628D01*
X871994Y-218753D01*
X868064Y-217003D01*
X867191Y-214961D01*
X867628Y-213503D01*
X868501Y-212628D01*
X869811Y-212337D01*
X871121Y-212628D01*
X872431Y-213503D01*
G01X887311Y-212337D02*
Y-224003D01*
G01Y-207670D02*
X886874Y-207378D01*
Y-206795D01*
X887311Y-206503D01*
X887748Y-206795D01*
Y-207378D01*
X887311Y-207670D01*
G01X901754Y-228378D02*
X903283Y-229545D01*
X905029Y-229836D01*
X906557Y-229545D01*
X907868Y-228087D01*
X908741Y-226045D01*
Y-212337D01*
G01Y-214670D02*
X907868Y-213503D01*
X906557Y-212628D01*
X905029Y-212337D01*
X903283Y-212920D01*
X902191Y-214086D01*
X901317Y-216128D01*
X900881Y-218170D01*
X901099Y-219920D01*
X901973Y-221962D01*
X903283Y-223420D01*
X905029Y-224003D01*
X906339Y-223711D01*
X907868Y-222545D01*
X908741Y-221379D01*
G01X918599Y-224003D02*
Y-212337D01*
G01Y-215253D02*
X919473Y-213795D01*
X920783Y-212628D01*
X922529Y-212337D01*
X924057Y-212628D01*
X925368Y-213795D01*
X926023Y-215836D01*
Y-224003D01*
G01X936536Y-216128D02*
X943523D01*
X942868Y-214086D01*
X941776Y-212920D01*
X940248Y-212337D01*
X938719Y-212628D01*
X937409Y-213503D01*
X936536Y-215545D01*
X936099Y-217295D01*
Y-219045D01*
X936536Y-220795D01*
X937628Y-222545D01*
X938938Y-223711D01*
X940466Y-224003D01*
X941994Y-223420D01*
X943523Y-221670D01*
G01X954254Y-224003D02*
Y-212337D01*
G01Y-214670D02*
X955346Y-213503D01*
X956438Y-212628D01*
X957966Y-212337D01*
X959057Y-212628D01*
X960368Y-213503D01*
G01X874194Y-265503D02*
X875286Y-267253D01*
X876596Y-268420D01*
X878124Y-269003D01*
X879871Y-268420D01*
X881181Y-267253D01*
X882491Y-265503D01*
X882928Y-263170D01*
Y-251503D01*
G01X896061Y-269003D02*
X894314Y-268711D01*
X892786Y-267545D01*
X891476Y-265795D01*
X890602Y-263753D01*
X890166Y-261420D01*
Y-259086D01*
X890602Y-256753D01*
X891476Y-254711D01*
X892786Y-252962D01*
X894314Y-251795D01*
X896061Y-251503D01*
X897807Y-251795D01*
X899336Y-252962D01*
X900646Y-254711D01*
X901520Y-256753D01*
X901956Y-259086D01*
Y-261420D01*
X901520Y-263753D01*
X900646Y-265795D01*
X899336Y-267545D01*
X897807Y-268711D01*
X896061Y-269003D01*
G01X913561D02*
Y-261128D01*
X909194Y-251503D01*
G01X917928D02*
X913561Y-261128D01*
G01X1001011Y-269003D02*
Y-251503D01*
X998391Y-255003D01*
G01Y-269003D02*
X1003631D01*
G01X1014363Y-254420D02*
X1015673Y-252670D01*
X1017201Y-251795D01*
X1018948Y-251503D01*
X1021131Y-252086D01*
X1022659Y-253545D01*
X1023096Y-255294D01*
X1022878Y-257045D01*
X1022004Y-258503D01*
X1017638Y-261420D01*
X1015673Y-263461D01*
X1014363Y-266379D01*
X1013926Y-269003D01*
X1023096D01*
G01X1032081Y-269586D02*
X1039941Y-251503D01*
G01X1048708Y-265503D02*
X1050017Y-267545D01*
X1051764Y-268711D01*
X1053729Y-269003D01*
X1055476Y-268711D01*
X1057223Y-267253D01*
X1058314Y-265503D01*
X1058533Y-263753D01*
X1058096Y-261712D01*
X1056568Y-260253D01*
X1055039Y-259670D01*
X1053074D01*
G01X1055039D02*
X1056349Y-258795D01*
X1057441Y-257337D01*
X1057878Y-255587D01*
X1057441Y-253836D01*
X1056349Y-252378D01*
X1054384Y-251503D01*
X1052419Y-251795D01*
X1050454Y-252962D01*
G01X1071011Y-251503D02*
X1069264Y-252086D01*
X1067954Y-253545D01*
X1067081Y-255294D01*
X1066426Y-257628D01*
X1066208Y-260253D01*
X1066426Y-262878D01*
X1067081Y-265212D01*
X1067954Y-266962D01*
X1069264Y-268420D01*
X1071011Y-269003D01*
X1072757Y-268420D01*
X1074068Y-266962D01*
X1074941Y-265212D01*
X1075596Y-262878D01*
X1075814Y-260253D01*
X1075596Y-257628D01*
X1074941Y-255294D01*
X1074068Y-253545D01*
X1072757Y-252086D01*
X1071011Y-251503D01*
G01X1084581Y-269586D02*
X1092441Y-251503D01*
G01X1101863Y-254420D02*
X1103173Y-252670D01*
X1104701Y-251795D01*
X1106448Y-251503D01*
X1108631Y-252086D01*
X1110159Y-253545D01*
X1110596Y-255294D01*
X1110378Y-257045D01*
X1109504Y-258503D01*
X1105138Y-261420D01*
X1103173Y-263461D01*
X1101863Y-266379D01*
X1101426Y-269003D01*
X1110596D01*
G01X1123511Y-251503D02*
X1121764Y-252086D01*
X1120454Y-253545D01*
X1119581Y-255294D01*
X1118926Y-257628D01*
X1118708Y-260253D01*
X1118926Y-262878D01*
X1119581Y-265212D01*
X1120454Y-266962D01*
X1121764Y-268420D01*
X1123511Y-269003D01*
X1125257Y-268420D01*
X1126568Y-266962D01*
X1127441Y-265212D01*
X1128096Y-262878D01*
X1128314Y-260253D01*
X1128096Y-257628D01*
X1127441Y-255294D01*
X1126568Y-253545D01*
X1125257Y-252086D01*
X1123511Y-251503D01*
G01X1141011Y-269003D02*
Y-251503D01*
X1138391Y-255003D01*
G01Y-269003D02*
X1143631D01*
G01X1154363Y-261712D02*
X1155891Y-259670D01*
X1157201Y-258503D01*
X1158948Y-257920D01*
X1160476Y-258503D01*
X1161568Y-259670D01*
X1162441Y-261420D01*
X1162659Y-263461D01*
X1162441Y-265212D01*
X1161568Y-266962D01*
X1160257Y-268420D01*
X1158729Y-269003D01*
X1156983Y-268420D01*
X1155454Y-266670D01*
X1154581Y-264045D01*
X1154363Y-261128D01*
X1154799Y-257337D01*
X1155454Y-255294D01*
X1156546Y-253253D01*
X1158074Y-251795D01*
X1159603Y-251503D01*
X1161131Y-252086D01*
X1162223Y-253545D01*
G01X1048708Y-224003D02*
Y-206503D01*
X1053074D01*
X1054821Y-207378D01*
X1056131Y-208545D01*
X1057223Y-210294D01*
X1058096Y-212337D01*
X1058314Y-215253D01*
X1058096Y-218170D01*
X1057223Y-220212D01*
X1056131Y-221962D01*
X1054821Y-223128D01*
X1053074Y-224003D01*
X1048708D01*
G01X1074941D02*
Y-212337D01*
G01Y-214378D02*
X1074068Y-213212D01*
X1072757Y-212628D01*
X1071229Y-212337D01*
X1069701Y-212920D01*
X1068391Y-214086D01*
X1067517Y-215836D01*
X1067081Y-218170D01*
X1067517Y-220503D01*
X1068391Y-222253D01*
X1069701Y-223420D01*
X1071229Y-224003D01*
X1072757Y-223711D01*
X1074068Y-222837D01*
X1074941Y-221670D01*
G01X1088511Y-206503D02*
Y-224003D01*
G01X1085454Y-212337D02*
X1091568D01*
G01X1102736Y-216128D02*
X1109723D01*
X1109068Y-214086D01*
X1107976Y-212920D01*
X1106448Y-212337D01*
X1104919Y-212628D01*
X1103609Y-213503D01*
X1102736Y-215545D01*
X1102299Y-217295D01*
Y-219045D01*
X1102736Y-220795D01*
X1103828Y-222545D01*
X1105138Y-223711D01*
X1106666Y-224003D01*
X1108194Y-223420D01*
X1109723Y-221670D01*
G54D27*
X208200Y320000D03*
G54D18*
X100200Y317000D03*
Y321000D03*
X197011Y317000D03*
X258200Y96500D03*
X258700Y160500D03*
X258200Y205000D03*
X274700Y131500D03*
Y135500D03*
G54D19*
X123200Y293000D03*
X209200Y309500D03*
X248700Y156500D03*
Y152500D03*
X258200Y88500D03*
Y197000D03*
G54D28*
X234700Y71000D03*
Y138500D03*
Y179500D03*
Y247000D03*
X242300Y71000D03*
Y138500D03*
Y179500D03*
Y247000D03*
G54D29*
X255200Y164500D03*
M02*
